# TIMECARD (Time Appliance Project (Time Card)) — schematic parts with pin connectivity, parts 877–1077 of 1119; source: Cadence DE-HDL packaged netlist (pstxprt.dat, pstxnet.dat, pstchip.dat)

R472  RESISTOR  0OHM -  pkg SMC_0402R_H016  page 24 : 1 = R_FT4232_I2C_SDA_OUT ; 2 = FT4232_I2C_SDA
R473  RESISTOR  0OHM -  pkg SMC_0402R_H016  page 24 : 1 = R_FT4232_I2C_SDA_IN ; 2 = FT4232_I2C_SDA
R474  RESISTOR  100KOHM 1%  pkg SMC_0402R_H016  page 24 : 1 = XP3R3V_FPGA ; 2 = FPGA_PCA9546_I2C_SDA
R475  RESISTOR  100KOHM 1%  pkg SMC_0402R_H016  page 24 : 1 = XP3R3V_FPGA ; 2 = FPGA_PCA9546_I2C_SCL
R476  RESISTOR  100KOHM 1%  pkg SMC_0402R_H016  page 24 : 1 = XP3R3V_FPGA ; 2 = FPGA_EEPROM_I2C_SDA
R477  RESISTOR  100KOHM 1%  pkg SMC_0402R_H016  page 24 : 1 = XP3R3V_FPGA ; 2 = FPGA_EEPROM_I2C_SCL
R478  RESISTOR  100KOHM 1%  pkg SMC_0402R_H016  page 24 : 1 = FT4232_I2C_SCL ; 2 = XP3R3V_FT4232
R479  RESISTOR  100KOHM 1%  pkg SMC_0402R_H016  page 24 : 1 = FT4232_I2C_SDA ; 2 = XP3R3V_FT4232
R480  RESISTOR  100KOHM 1%  pkg SMC_0402R_H016  page 24 : 1 = UART_FT4232_TX_FPGA_RX ; 2 = XP3R3V_FT4232
R481  RESISTOR  100KOHM 1%  pkg SMC_0402R_H016  page 24 : 1 = R_FT4232_CHC_RX ; 2 = XP3R3V_FT4232
R482  RESISTOR  4.7KOHM 1%  pkg SMC_0402R_H016  page 24 : 1 = XP3R3V_FPGA ; 2 = MUX3_SEL
R483  RESISTOR  1KOHM 1%  pkg SMC_0402R_H016  page 24 : 1 = SG ; 2 = MUX3_SEL
R484  RESISTOR  1KOHM 1%  pkg SMC_0402R_H016  page 24 : 1 = SG ; 2 = UNNAMED_524_RESISTOR_I463_2
R485  RESISTOR  33OHM 1%  pkg SMC_0402R_H016  page 24 : 1 = FPGA_OUT_MUX3_SEL ; 2 = MUX3_SEL
R486  RESISTOR  33OHM 1%  pkg SMC_0402R_H016  page 24 : 1 = FT4232_MUX3_SEL ; 2 = MUX3_SEL
R487  RESISTOR  4.7KOHM 1%  pkg SMC_0402R_H016  page 33 : 1 = UNNAMED_525_CAPACITOR_I16_1 ; 2 = UNNAMED_525_CAPACITOR_I14_1
R488  RESISTOR  10KOHM 1%  pkg SMC_0402R_H016  page 33 : 1 = UNNAMED_525_CAPACITOR_I14_1 ; 2 = SG
R489  RESISTOR  3.92KOHM 1%  pkg SMC_0402R  page 33 : 1 = UNNAMED_525_ISL80101IRAJZDFN10_ ; 2 = SG
R490  RESISTOR  10KOHM 1%  pkg SMC_0402R_H016  page 33 : 1 = XP3R3V_FT4232 ; 2 = UNNAMED_525_ISL80101IRAJZDFN10_
R491  RESISTOR  3.24KOHM 1%  pkg SMC_0402R_H014  page 33 : 1 = UNNAMED_525_ISL80101IRAJZDFN10_ ; 2 = SG
R492  RESISTOR  0OHM -  pkg SMC_0402R_H016  page 23 : 1 = UNNAMED_12_CAPACITOR_I318_2 ; 2 = UNNAMED_12_74HCT2G125DPTSSOP8_I
R493  RESISTOR  0OHM -  pkg SMC_0402R_H016  page 23 : 1 = UNNAMED_12_CAPACITOR_I321_2 ; 2 = UNNAMED_12_74HCT2G125DPTSSOP8_3
R494  RESISTOR  0OHM -  pkg SMC_0402R_H016  page 23 : 1 = UNNAMED_12_CAPACITOR_I328_2 ; 2 = UNNAMED_12_74HCT2G125DPTSSOP8_6
R495  RESISTOR  0OHM -  pkg SMC_0402R_H016  page 23 : 1 = UNNAMED_12_CAPACITOR_I332_2 ; 2 = UNNAMED_12_74HCT2G125DPTSSOP8_9
R496  RESISTOR  1MOHM 1%  pkg SMC_0402R_H016  page 23 : 1 = SG ; 2 = BF_SMA3_SIG_IO_CONN
R497  RESISTOR  1MOHM 1%  pkg SMC_0402R_H016  page 23 : 1 = SG ; 2 = BF_SMA4_SIG_IO_CONN
R498  RESISTOR  1MOHM 1%  pkg SMC_0402R_H016  page 23 : 1 = SG ; 2 = BF_SMA1_SIG_IO_CONN
R499  RESISTOR  1MOHM 1%  pkg SMC_0402R_H016  page 23 : 1 = SG ; 2 = BF_SMA2_SIG_IO_CONN
R500  RESISTOR  4.7KOHM 1%  pkg SMC_0402R_H016  page 11 : 1 = SG ; 2 = ANT3_IN
R501  RESISTOR  4.7KOHM 1%  pkg SMC_0402R_H016  page 11 : 1 = SG ; 2 = ANT4_IN
R502  RESISTOR  4.7KOHM 1%  pkg SMC_0402R_H016  page 11 : 1 = XP3R3V_FPGA ; 2 = FPGA_IN_MAC_10MHZ_OUT
R503  RESISTOR  4.7KOHM 1%  pkg SMC_0402R_H016  page 11 : 1 = ANT2_IN ; 2 = SG
R504  RESISTOR  4.7KOHM 1%  pkg SMC_0402R_H016  page 11 : 1 = ANT1_IN ; 2 = SG
R1991  RESISTOR  10KOHM 1%  pkg SMC_0402R_H016  page 16 : 1 = XP3R3V_FPGA ; 2 = EEPROM_SDA
R1992  RESISTOR  4.7KOHM 1%  pkg SMC_0402R_H016  page 16 : 1 = XP3R3V_FPGA ; 2 = SN_EEPROM_WP
SP1  SOLDER_PREFORM  pkg 0201_SOLDER_PREFORM_4MIL  page 32 : 1 = SG ; 2 = XP5R0V_AGND
SP2  SOLDER_PREFORM  pkg 0201_SOLDER_PREFORM_4MIL  page 28 : 1 = SG ; 2 = XP3R3V_AGND
SP3  SOLDER_PREFORM  pkg 0201_SOLDER_PREFORM_4MIL  page 29 : 1 = SG ; 2 = XP1R0V_AGND
SP4  SOLDER_PREFORM  pkg 0201_SOLDER_PREFORM_4MIL  page 34 : 1 = NC ; 2 = NC
SP5  SOLDER_PREFORM  pkg 0201_SOLDER_PREFORM_4MIL  page 34 : 1 = NC ; 2 = NC
SP6  SOLDER_PREFORM  pkg 0201_SOLDER_PREFORM_4MIL  page 34 : 1 = NC ; 2 = NC
SP7  SOLDER_PREFORM  pkg 0201_SOLDER_PREFORM_4MIL  page 34 : 1 = NC ; 2 = NC
SP8  SOLDER_PREFORM  pkg 0201_SOLDER_PREFORM_4MIL  page 34 : 1 = NC ; 2 = NC
SP9  SOLDER_PREFORM  pkg 0201_SOLDER_PREFORM_4MIL  page 34 : 1 = NC ; 2 = NC
SP10  SOLDER_PREFORM  pkg 0201_SOLDER_PREFORM_4MIL  page 34 : 1 = NC ; 2 = NC
SP11  SOLDER_PREFORM  pkg 0201_SOLDER_PREFORM_4MIL  page 34 : 1 = NC ; 2 = NC
SP12  SOLDER_PREFORM  pkg 0201_SOLDER_PREFORM_4MIL  page 34 : 1 = NC ; 2 = NC
SP13  SOLDER_PREFORM  pkg 0201_SOLDER_PREFORM_4MIL  page 34 : 1 = NC ; 2 = NC
SP14  SOLDER_PREFORM  pkg 0201_SOLDER_PREFORM_4MIL  page 34 : 1 = NC ; 2 = NC
SP15  SOLDER_PREFORM  pkg 0201_SOLDER_PREFORM_4MIL  page 34 : 1 = NC ; 2 = NC
SP16  SOLDER_PREFORM  pkg 0201_SOLDER_PREFORM_4MIL  page 34 : 1 = NC ; 2 = NC
SP17  SOLDER_PREFORM  pkg 0201_SOLDER_PREFORM_4MIL  page 34 : 1 = NC ; 2 = NC
SP18  SOLDER_PREFORM  pkg 0201_SOLDER_PREFORM_4MIL  page 34 : 1 = NC ; 2 = NC
SP19  SOLDER_PREFORM  pkg 0201_SOLDER_PREFORM_4MIL  page 34 : 1 = NC ; 2 = NC
SP20  SOLDER_PREFORM  pkg 0201_SOLDER_PREFORM_4MIL  page 34 : 1 = NC ; 2 = NC
SP21  SOLDER_PREFORM  pkg 0201_SOLDER_PREFORM_4MIL  page 34 : 1 = NC ; 2 = NC
SP22  SOLDER_PREFORM  pkg 0201_SOLDER_PREFORM_4MIL  page 34 : 1 = NC ; 2 = NC
SP23  SOLDER_PREFORM  pkg 0201_SOLDER_PREFORM_4MIL  page 34 : 1 = NC ; 2 = NC
SP24  SOLDER_PREFORM  pkg 0201_SOLDER_PREFORM_4MIL  page 34 : 1 = NC ; 2 = NC
SP25  SOLDER_PREFORM  pkg 0201_SOLDER_PREFORM_4MIL  page 34 : 1 = NC ; 2 = NC
SP26  SOLDER_PREFORM  pkg 0201_SOLDER_PREFORM_4MIL  page 34 : 1 = NC ; 2 = NC
SP27  SOLDER_PREFORM  pkg 0201_SOLDER_PREFORM_4MIL  page 34 : 1 = NC ; 2 = NC
SP28  SOLDER_PREFORM  pkg 0201_SOLDER_PREFORM_4MIL  page 34 : 1 = NC ; 2 = NC
SP29  SOLDER_PREFORM  pkg 0201_SOLDER_PREFORM_4MIL  page 34 : 1 = NC ; 2 = NC
SP30  SOLDER_PREFORM  pkg 0201_SOLDER_PREFORM_4MIL  page 34 : 1 = NC ; 2 = NC
SP31  SOLDER_PREFORM  pkg 0201_SOLDER_PREFORM_4MIL  page 34 : 1 = NC ; 2 = NC
SP32  SOLDER_PREFORM  pkg 0201_SOLDER_PREFORM_4MIL  page 34 : 1 = NC ; 2 = NC
SP33  SOLDER_PREFORM  pkg 0201_SOLDER_PREFORM_4MIL  page 34 : 1 = NC ; 2 = NC
SP34  SOLDER_PREFORM  pkg 0201_SOLDER_PREFORM_4MIL  page 34 : 1 = NC ; 2 = NC
SP35  SOLDER_PREFORM  pkg 0201_SOLDER_PREFORM_4MIL  page 34 : 1 = NC ; 2 = NC
SP36  SOLDER_PREFORM  pkg 0201_SOLDER_PREFORM_4MIL  page 34 : 1 = NC ; 2 = NC
SP37  SOLDER_PREFORM  pkg 0201_SOLDER_PREFORM_4MIL  page 34 : 1 = NC ; 2 = NC
SP38  SOLDER_PREFORM  pkg 0201_SOLDER_PREFORM_4MIL  page 34 : 1 = NC ; 2 = NC
SP39  SOLDER_PREFORM  pkg 0201_SOLDER_PREFORM_4MIL  page 34 : 1 = NC ; 2 = NC
SP40  SOLDER_PREFORM  pkg 0201_SOLDER_PREFORM_4MIL  page 34 : 1 = NC ; 2 = NC
SP41  SOLDER_PREFORM  pkg 0201_SOLDER_PREFORM_4MIL  page 34 : 1 = NC ; 2 = NC
SP42  NULL  pkg DUMMY  page 34
SP43  NULL  pkg DUMMY  page 34
SP44  NULL  pkg DUMMY  page 34
SP45  NULL  pkg DUMMY  page 34
SP46  NULL  pkg DUMMY  page 34
SP47  NULL  pkg DUMMY  page 34
SP48  NULL  pkg DUMMY  page 34
SP49  NULL  pkg DUMMY  page 34
SP50  NULL  pkg DUMMY  page 34
SP51  NULL  pkg DUMMY  page 34
SP52  NULL  pkg DUMMY  page 34
SP53  NULL  pkg DUMMY  page 34
SP54  NULL  pkg DUMMY  page 34
SP55  NULL  pkg DUMMY  page 34
SP56  NULL  pkg DUMMY  page 34
SP57  NULL  pkg DUMMY  page 34
SP58  NULL  pkg DUMMY  page 34
SP59  NULL  pkg DUMMY  page 34
SP60  NULL  pkg DUMMY  page 34
SP61  NULL  pkg DUMMY  page 34
SP62  NULL  pkg DUMMY  page 34
SP63  NULL  pkg DUMMY  page 34
SP64  NULL  pkg DUMMY  page 34
SP65  NULL  pkg DUMMY  page 34
SP66  NULL  pkg DUMMY  page 34
SP67  NULL  pkg DUMMY  page 34
SP68  NULL  pkg DUMMY  page 34
SP69  NULL  pkg DUMMY  page 34
SP70  NULL  pkg DUMMY  page 34
SP71  NULL  pkg DUMMY  page 34
TP1  TP_PIONT  pkg TP010CT020B030_PTH  page 20 : 1 = BNO080_EVN_SDA
TP2  TP_PIONT  pkg TP010CT020B030_PTH  page 20 : 1 = BNO080_EVN_SCL
TP3  TP_PIONT  pkg TP010CT020B030_PTH  page 25 : 1 = XP3R3V_FT4232
TP4  TP_PIONT  pkg TP010CT020B030_PTH  page 25 : 1 = XP5R0V_FT4232
TP5  TP_PIONT  pkg TP010CT020B030_PTH  page 24 : 1 = UNNAMED_524_FT4232HLREELQFP64_I
TP6  TP_PIONT  pkg TP010CT020B030_PTH  page 24 : 1 = UNNAMED_524_FT4232HLREELQFP64_1
TP7  TP_PIONT  pkg TP010CT020B030_PTH  page 24 : 1 = UNNAMED_524_FT4232HLREELQFP64_2
TP8  TP_PIONT  pkg TP010CT020B030_PTH  page 24 : 1 = UNNAMED_524_FT4232HLREELQFP64_3
TP9  TP_PIONT  pkg TP010CT020B030_PTH  page 24 : 1 = UNNAMED_524_FT4232HLREELQFP64_4
TP10  TP_PIONT  pkg TP010CT020B030_PTH  page 24 : 1 = UNNAMED_524_FT4232HLREELQFP64_5
TP11  TP_PIONT  pkg TP010CT020B030_PTH  page 25 : 1 = FT_USB_DETECT
TP12  TP_PIONT  pkg TP010CT020B030_PTH  page 25 : 1 = MUX3_SEL
TP13  TP_PIONT  pkg TP010CT020B030_PTH  page 25 : 1 = MUX2_SEL
TP14  TP_PIONT  pkg TP010CT020B030_PTH  page 25 : 1 = MUX1_SEL
TP15  TP_PIONT  pkg TP010CT020B030_PTH  page 25 : 1 = GPS_RST_N
TP16  TP_PIONT  pkg TP010CT020B030_PTH  page 25 : 1 = R_BNO080_RST_N
TP17  TP_PIONT  pkg TP010CT020B030_PTH  page 25 : 1 = R_BNO080_INT_N
TP18  TP_PIONT  pkg TP010CT020B030_PTH  page 25 : 1 = R_BNO080_BOOT_N
TP19  TP_PIONT  pkg TP010CT020B030_PTH  page 25 : 1 = SN_EEPROM_WP
TP20  TP_PIONT  pkg TP010CT020B030_PTH  page 25 : 1 = SEC_EEPROM_WP
TP21  TP_PIONT  pkg TP010CT020B030_PTH  page 25 : 1 = PCA9546_RST_N
TP22  TP_PIONT  pkg TP010CT020B030_PTH  page 25 : 1 = FPGA_IN_LM75B_INT3_N
TP23  TP_PIONT  pkg TP010CT020B030_PTH  page 25 : 1 = FPGA_IN_LM75B_INT2_N
TP24  TP_PIONT  pkg TP010CT020B030_PTH  page 25 : 1 = FPGA_IN_LM75B_INT1_N
TP25  TP_PIONT  pkg TP010CT020B030_PTH  page 25 : 1 = RGB_LED_SHUTDOWN_N
TP26  TP_PIONT  pkg TP010CT020B030_PTH  page 25 : 1 = R_SHT3X_RST_N
TP27  TP_PIONT  pkg TP010CT020B030_PTH  page 25 : 1 = R_SHT3X_ALERT_N
TP28  TP_PIONT  pkg TP010CT020B030_PTH  page 25 : 1 = SMA1_SIG_IN_BF_EN_N
TP29  TP_PIONT  pkg TP010CT020B030_PTH  page 25 : 1 = SMA2_SIG_IN_BF_EN_N
TP30  TP_PIONT  pkg TP010CT020B030_PTH  page 25 : 1 = SMA3_SIG_IN_BF_EN_N
TP31  TP_PIONT  pkg TP010CT020B030_PTH  page 25 : 1 = SMA4_SIG_IN_BF_EN_N
TP32  TP_PIONT  pkg TP010CT020B030_PTH  page 25 : 1 = SMA1_SIG_OUT_BF_EN_N
TP33  TP_PIONT  pkg TP010CT020B030_PTH  page 25 : 1 = SMA2_SIG_OUT_BF_EN_N
TP34  TP_PIONT  pkg TP010CT020B030_PTH  page 25 : 1 = SMA3_SIG_OUT_BF_EN_N
TP35  TP_PIONT  pkg TP010CT020B030_PTH  page 25 : 1 = SMA4_SIG_OUT_BF_EN_N
TP36  TP_PIONT  pkg TP010CT020B030_PTH  page 25 : 1 = XP12R0V_A_PG
TP37  TP_PIONT  pkg TP010CT020B030_PTH  page 25 : 1 = XP12R0V_A_FLTB
TP38  TP_PIONT  pkg TP010CT020B030_PTH  page 25 : 1 = XP3R3V_PG
TP39  TP_PIONT  pkg TP010CT020B030_PTH  page 25 : 1 = XP1R0V_FPGA_PG
TP40  TP_PIONT  pkg TP010CT020B030_PTH  page 25 : 1 = XP1R2V_FPGA_PG
TP41  TP_PIONT  pkg TP010CT020B030_PTH  page 25 : 1 = XP1R8V_FPGA_PG
TP42  TP_PIONT  pkg TP010CT020B030_PTH  page 25 : 1 = XP12R0V_IN
TP43  TP_PIONT  pkg TP010CT020B030_PTH  page 25 : 1 = XP12R0V_A_EN
TP44  TP_PIONT  pkg TP010CT020B030_PTH  page 25 : 1 = FPGA_DONE
TP45  TP_PIONT  pkg TP010CT020B030_PTH  page 25 : 1 = FPGA_PROGRAM_N
TP46  TP_PIONT  pkg TP010CT020B030_PTH  page 25 : 1 = FPGA_CFG_INIT_N
TP47  TP_PIONT  pkg TP010CT020B030_PTH  page 25 : 1 = FPGA_MGTRREF
TP48  TP_PIONT  pkg TP010CT020B030_PTH  page 25 : 1 = PCIE_CONN_PERST_N
TP49  TP_PIONT  pkg TP010CT020B030_PTH  page 25 : 1 = CLK_200M_OE
TP50  TP_PIONT  pkg TP010CT020B030_PTH  page 25 : 1 = CLK_125M_OE
TP51  TP_PIONT  pkg TP010CT020B030_PTH  page 25 : 1 = MAC_ALARM
TP52  TP_PIONT  pkg TP010CT020B030_PTH  page 25 : 1 = XP12R0V
TP53  TP_PIONT  pkg TP010CT020B030_PTH  page 25 : 1 = XP3R3V
TP54  TP_PIONT  pkg TP010CT020B030_PTH  page 25 : 1 = XP1R0V_FPGA
TP55  TP_PIONT  pkg TP010CT020B030_PTH  page 25 : 1 = XP1R2V_FPGA
TP56  TP_PIONT  pkg TP010CT020B030_PTH  page 25 : 1 = XP1R8V_FPGA
TP57  TP_PIONT  pkg TP010CT020B030_PTH  page 25 : 1 = XP2R5V_FPGA
TP58  TP_PIONT  pkg TP010CT020B030_PTH  page 25 : 1 = XP3R3V_FPGA
TP59  TP_PIONT  pkg TP010CT020B030_PTH  page 25 : 1 = XP3R3V_EN
TP60  TP_PIONT  pkg TP010CT020B030_PTH  page 25 : 1 = XP5R0V
TP61  TP_PIONT  pkg TP010CT020B030_PTH  page 20 : 1 = UNNAMED_9_BNO080LGA28_I29_HCS
TP62  TP_PIONT  pkg TP010CT020B030_PTH  page 25 : 1 = R_MAC_BITEOUT
TP78  TP_PIONT  pkg TP010CT020B030_PTH  page 25 : 1 = IO_L20P_16
TP132  TP_PIONT  pkg TP010CT020B030_PTH  page 25 : 1 = IO_L20P_34
TP133  TP_PIONT  pkg TP010CT020B030_PTH  page 25 : 1 = IO_L20N_34
TP134  TP_PIONT  pkg TP010CT020B030_PTH  page 25 : 1 = IO_L21P_34
TP135  TP_PIONT  pkg TP010CT020B030_PTH  page 25 : 1 = IO_L21N_34
TP136  TP_PIONT  pkg TP010CT020B030_PTH  page 25 : 1 = IO_L22P_34
TP137  TP_PIONT  pkg TP010CT020B030_PTH  page 25 : 1 = IO_L22N_34
TP138  TP_PIONT  pkg TP010CT020B030_PTH  page 25 : 1 = IO_L23P_34
TP139  TP_PIONT  pkg TP010CT020B030_PTH  page 25 : 1 = IO_L23N_34
TP140  TP_PIONT  pkg TP010CT020B030_PTH  page 25 : 1 = IO_L24P_34
TP141  TP_PIONT  pkg TP010CT020B030_PTH  page 25 : 1 = IO_L24N_34
TP180  TP_PIONT  pkg TP010CT020B030_PTH  page 25 : 1 = IO_L20N_16
TP181  TP_PIONT  pkg TP010CT020B030_PTH  page 25 : 1 = IO_L21P_16
TP182  TP_PIONT  pkg TP010CT020B030_PTH  page 25 : 1 = IO_L21N_16
TP183  TP_PIONT  pkg TP010CT020B030_PTH  page 25 : 1 = IO_L22P_16
TP184  TP_PIONT  pkg TP010CT020B030_PTH  page 25 : 1 = IO_L22N_16
TP185  TP_PIONT  pkg TP010CT020B030_PTH  page 25 : 1 = IO_L23P_16
TP186  TP_PIONT  pkg TP010CT020B030_PTH  page 25 : 1 = IO_L23N_16
TP187  TP_PIONT  pkg TP010CT020B030_PTH  page 25 : 1 = IO_L24P_16
TP188  TP_PIONT  pkg TP010CT020B030_PTH  page 25 : 1 = IO_L24N_16
TP193  TP_PIONT  pkg TP010CT020B030_PTH  page 25 : 1 = IO_L21P_35
TP194  TP_PIONT  pkg TP010CT020B030_PTH  page 25 : 1 = IO_L21N_35
TP195  TP_PIONT  pkg TP010CT020B030_PTH  page 25 : 1 = IO_L23P_35
TP196  TP_PIONT  pkg TP010CT020B030_PTH  page 25 : 1 = IO_L23N_35
TP199  TP_PIONT  pkg TP010CT020B030_PTH  page 25 : 1 = IO_L20P_35
TP200  TP_PIONT  pkg TP010CT020B030_PTH  page 25 : 1 = IO_L20N_35
TP201  TP_PIONT  pkg TP010CT020B030_PTH  page 25 : 1 = IO_L22P_35
TP202  TP_PIONT  pkg TP010CT020B030_PTH  page 25 : 1 = IO_L22N_35
TP203  TP_PIONT  pkg TP010CT020B030_PTH  page 25 : 1 = IO_L24P_35
TP204  TP_PIONT  pkg TP010CT020B030_PTH  page 25 : 1 = IO_L24N_35

U1  MP5022CGQV_Z_QFN22  pkg QFN26_118X197_P197_TR049X010  page 27
  1  EN  IN  = XP12R0V_A_EN
  2  LOADEN  IN  = UNNAMED_15_MP5022CGQVZQFN22_I_2
  3  ENTM  BI  = UNNAMED_15_MP5022CGQVZQFN22_I21
  4  TIMER  BI  = XP12R0V_A_TIMER
  5  ISET  BI  = XP12R0V_A_ISET
  6  SS  BI  = XP12R0V_A_SS
  7  GND  GROUND  = SG
  8  IMON  OUT  = XP12R0V_A_IMON
  9  FLTB  OUT  = XP12R0V_A_FLTB
  10  PG  OUT  = XP12R0V_A_PG
  11  OV  IN  = XP12R0V_A_OV
  12  AVIN  POWER  = XP12R0V_A_AVIN
  13  VOUT_1  OUT  = XP12R0V
  14  VOUT_2  OUT  = XP12R0V
  15  VOUT_3  OUT  = XP12R0V
  16  VOUT_4  OUT  = XP12R0V
  17  VOUT_5  OUT  = XP12R0V
  18  VOUT_6  OUT  = XP12R0V
  19  VOUT_7  OUT  = XP12R0V
  20  VOUT_8  OUT  = XP12R0V
  21  VIN_1  POWER  = XP12R0V_IN
  22  VIN_2  POWER  = XP12R0V_IN
  23  VIN_3  POWER  = XP12R0V_IN
  24  VIN_4  POWER  = XP12R0V_IN
  25  VIN_5  POWER  = XP12R0V_IN
  26  VIN_6  POWER  = XP12R0V_IN

U2  G220_10198_01  pkg SOP8_154_P050_V1  page 9
  1  EN  BI  = UNNAMED_3_G2201019801_I100_EN
  2  SCLOUT  OUT  = PCIE_SMCLK
  3  SCLIN  IN  = PCIE_CONN_SMCLK
  4  GND  GROUND  = SG
  5  READY  BI  = NC
  6  SDAIN  IN  = PCIE_CONN_SMDAT
  7  SDAOUT  OUT  = PCIE_SMDAT
  8  VCC  POWER  = XP3R3V_FPGA

U3  74LVC1G07_SC70_5  pkg SC70_5V1  page 9
  1  NC  NC  = NC
  2  A  IN  = PCIE_CONN_PERST_N
  3  GND  GROUND  = SG
  4  Y  OUT  = BF_PCIE_PERST_N
  5  VCC  POWER  = XP3R3V_FPGA
